# T6G (Grand Teton) — schematic netlist excerpt (pin names and nets, part order shuffled) for the footprints in the layout excerpt that follows; sources: Cadence DE-HDL packaged netlist, KiCad conversion of 04192023_DAF0TMB3IC0_F0TG_MB_C_brd_V02_OCP.brd

R6777  Q_RES  0 5% CHIP  pkg 0402LF  page 81 : A = RST_SMB_RT_R2_N ; B = RST_SMB_RT_R1_N
PC497  Q_CAP  0.1UF 25V 10% X7R  pkg 0402  page 194 : A = PVDDCR_CPU0_P0 ; B = GND

(kicad_pcb
	(version 20260206)
	(generator "pcbnew")
	(generator_version "10.0")
	(general
		(thickness 1.6)
		(legacy_teardrops no)
	)
	(paper "A4")
	(title_block
		(title "04192023_DAF0TMB3IC0_F0TG_MB_C_brd_V02_OCP.brd")
		(comment 1 "Grand Teton / footprints 1255-1256 of 8354")
	)
	(layers
		(0 "F.Cu" signal "TOP")
		(4 "In1.Cu" signal "GND")
		(6 "In2.Cu" signal "IN1")
		(8 "In3.Cu" signal "GND1")
		(10 "In4.Cu" signal "IN2")
		(12 "In5.Cu" signal "GND2")
		(14 "In6.Cu" signal "IN3")
		(16 "In7.Cu" signal "GND3")
		(18 "In8.Cu" signal "VCC")
		(20 "In9.Cu" signal "VCC1")
		(22 "In10.Cu" signal "GND4")
		(24 "In11.Cu" signal "IN4")
		(26 "In12.Cu" signal "GND5")
		(28 "In13.Cu" signal "IN5")
		(30 "In14.Cu" signal "GND6")
		(32 "In15.Cu" signal "IN6")
		(34 "In16.Cu" signal "GND7")
		(2 "B.Cu" signal "BOTTOM")
		(9 "F.Adhes" user "F.Adhesive")
		(11 "B.Adhes" user "B.Adhesive")
		(13 "F.Paste" user "Package Geometry/Pastemask Top")
		(15 "B.Paste" user "Package Geometry/Pastemask Bottom")
		(5 "F.SilkS" user "Ref Des/Silkscreen Top")
		(7 "B.SilkS" user "Ref Des/Silkscreen Bottom")
		(1 "F.Mask" user "Board Geometry/Soldermask Top")
		(3 "B.Mask" user "Board Geometry/Soldermask Bottom")
		(17 "Dwgs.User" user "User.Drawings")
		(19 "Cmts.User" user "User.Comments")
		(21 "Eco1.User" user "User.Eco1")
		(23 "Eco2.User" user "User.Eco2")
		(25 "Edge.Cuts" user "Board Geometry/Outline")
		(27 "Margin" user)
		(31 "F.CrtYd" user "Package Geometry/Place Bound Top")
		(29 "B.CrtYd" user "Package Geometry/Place Bound Bottom")
		(35 "F.Fab" user "Ref Des/Assembly Top")
		(33 "B.Fab" user "Ref Des/Assembly Bottom")
	)
	(footprint ""
		(layer "F.Cu")
		(at 343.096088 -171.746672 -90)
		(property "Reference" "PC497"
			(at 0 0 270)
			(layer "F.SilkS")
			(hide yes)
			(effects
				(font
					(size 1.27 1.27)
				)
			)
		)
		(property "Value" ""
			(at 0 0 270)
			(layer "F.Fab")
			(effects
				(font
					(size 1.27 1.27)
				)
			)
		)
		(duplicate_pad_numbers_are_jumpers no)
		(fp_line
			(start -0.7874 0.4064)
			(end -0.7874 -0.4064)
			(stroke
				(width 0.1524)
				(type default)
			)
			(layer "F.SilkS")
		)
		(fp_line
			(start 0.7874 0.4064)
			(end -0.7874 0.4064)
			(stroke
				(width 0.1524)
				(type default)
			)
			(layer "F.SilkS")
		)
		(fp_line
			(start -0.7874 -0.4064)
			(end 0.7874 -0.4064)
			(stroke
				(width 0.1524)
				(type default)
			)
			(layer "F.SilkS")
		)
		(fp_line
			(start 0.7874 -0.4064)
			(end 0.7874 0.4064)
			(stroke
				(width 0.1524)
				(type default)
			)
			(layer "F.SilkS")
		)
		(fp_line
			(start -0.67945 0.3048)
			(end -0.67945 -0.305054)
			(stroke
				(width 0.1)
				(type default)
			)
			(layer "F.Fab")
		)
		(fp_line
			(start -0.12065 0.3048)
			(end -0.67945 0.3048)
			(stroke
				(width 0.1)
				(type default)
			)
			(layer "F.Fab")
		)
		(fp_line
			(start 0.120396 0.3048)
			(end 0.120396 0.2794)
			(stroke
				(width 0.1)
				(type default)
			)
			(layer "F.Fab")
		)
		(fp_line
			(start 0.67945 0.3048)
			(end 0.120396 0.3048)
			(stroke
				(width 0.1)
				(type default)
			)
			(layer "F.Fab")
		)
		(fp_line
			(start -0.12065 0.2794)
			(end -0.12065 0.3048)
			(stroke
				(width 0.1)
				(type default)
			)
			(layer "F.Fab")
		)
		(fp_line
			(start 0.120396 0.2794)
			(end -0.12065 0.2794)
			(stroke
				(width 0.1)
				(type default)
			)
			(layer "F.Fab")
		)
		(fp_line
			(start -0.12065 -0.2794)
			(end 0.12065 -0.2794)
			(stroke
				(width 0.1)
				(type default)
			)
			(layer "F.Fab")
		)
		(fp_line
			(start 0.12065 -0.2794)
			(end 0.12065 -0.3048)
			(stroke
				(width 0.1)
				(type default)
			)
			(layer "F.Fab")
		)
		(fp_line
			(start 0.12065 -0.3048)
			(end 0.67945 -0.3048)
			(stroke
				(width 0.1)
				(type default)
			)
			(layer "F.Fab")
		)
		(fp_line
			(start 0.67945 -0.3048)
			(end 0.67945 0.3048)
			(stroke
				(width 0.1)
				(type default)
			)
			(layer "F.Fab")
		)
		(fp_line
			(start -0.67945 -0.305054)
			(end -0.12065 -0.305054)
			(stroke
				(width 0.1)
				(type default)
			)
			(layer "F.Fab")
		)
		(fp_line
			(start -0.12065 -0.305054)
			(end -0.12065 -0.2794)
			(stroke
				(width 0.1)
				(type default)
			)
			(layer "F.Fab")
		)
		(pad "1" smd circle
			(at -0.40005 0 270)
			(size 0 0)
			(layers "F.Cu" "F.Mask" "F.Paste")
			(net "PVDDCR_CPU0_P0")
		)
		(pad "2" smd circle
			(at 0.40005 0 270)
			(size 0 0)
			(layers "F.Cu" "F.Mask" "F.Paste")
			(net "GND")
		)
	)
	(footprint ""
		(layer "F.Cu")
		(at 201.137266 -121.795794)
		(property "Reference" "R6777"
			(at 0 0 0)
			(layer "F.SilkS")
			(hide yes)
			(effects
				(font
					(size 1.27 1.27)
				)
			)
		)
		(property "Value" ""
			(at 0 0 0)
			(layer "F.Fab")
			(effects
				(font
					(size 1.27 1.27)
				)
			)
		)
		(duplicate_pad_numbers_are_jumpers no)
		(fp_line
			(start -0.7874 -0.4064)
			(end 0.7874 -0.4064)
			(stroke
				(width 0.1524)
				(type default)
			)
			(layer "F.SilkS")
		)
		(fp_line
			(start -0.7874 0.4064)
			(end -0.7874 -0.4064)
			(stroke
				(width 0.1524)
				(type default)
			)
			(layer "F.SilkS")
		)
		(fp_line
			(start 0.7874 -0.4064)
			(end 0.7874 0.4064)
			(stroke
				(width 0.1524)
				(type default)
			)
			(layer "F.SilkS")
		)
		(fp_line
			(start 0.7874 0.4064)
			(end -0.7874 0.4064)
			(stroke
				(width 0.1524)
				(type default)
			)
			(layer "F.SilkS")
		)
		(fp_line
			(start -0.67945 -0.305054)
			(end -0.12065 -0.305054)
			(stroke
				(width 0.1)
				(type default)
			)
			(layer "F.Fab")
		)
		(fp_line
			(start -0.67945 0.3048)
			(end -0.67945 -0.305054)
			(stroke
				(width 0.1)
				(type default)
			)
			(layer "F.Fab")
		)
		(fp_line
			(start -0.12065 -0.305054)
			(end -0.12065 -0.2794)
			(stroke
				(width 0.1)
				(type default)
			)
			(layer "F.Fab")
		)
		(fp_line
			(start -0.12065 -0.2794)
			(end 0.12065 -0.2794)
			(stroke
				(width 0.1)
				(type default)
			)
			(layer "F.Fab")
		)
		(fp_line
			(start -0.12065 0.2794)
			(end -0.12065 0.3048)
			(stroke
				(width 0.1)
				(type default)
			)
			(layer "F.Fab")
		)
		(fp_line
			(start -0.12065 0.3048)
			(end -0.67945 0.3048)
			(stroke
				(width 0.1)
				(type default)
			)
			(layer "F.Fab")
		)
		(fp_line
			(start 0.120396 0.2794)
			(end -0.12065 0.2794)
			(stroke
				(width 0.1)
				(type default)
			)
			(layer "F.Fab")
		)
		(fp_line
			(start 0.120396 0.3048)
			(end 0.120396 0.2794)
			(stroke
				(width 0.1)
				(type default)
			)
			(layer "F.Fab")
		)
		(fp_line
			(start 0.12065 -0.3048)
			(end 0.67945 -0.3048)
			(stroke
				(width 0.1)
				(type default)
			)
			(layer "F.Fab")
		)
		(fp_line
			(start 0.12065 -0.2794)
			(end 0.12065 -0.3048)
			(stroke
				(width 0.1)
				(type default)
			)
			(layer "F.Fab")
		)
		(fp_line
			(start 0.67945 -0.3048)
			(end 0.67945 0.3048)
			(stroke
				(width 0.1)
				(type default)
			)
			(layer "F.Fab")
		)
		(fp_line
			(start 0.67945 0.3048)
			(end 0.120396 0.3048)
			(stroke
				(width 0.1)
				(type default)
			)
			(layer "F.Fab")
		)
		(pad "1" smd circle
			(at -0.40005 0)
			(size 0 0)
			(layers "F.Cu" "F.Mask" "F.Paste")
			(net "RST_SMB_RT_R2_N")
		)
		(pad "2" smd circle
			(at 0.40005 0)
			(size 0 0)
			(layers "F.Cu" "F.Mask" "F.Paste")
			(net "RST_SMB_RT_R1_N")
		)
	)
)
